(kicad_pcb
	(version 20260206)
	(generator "pcbnew")
	(generator_version "10.0")
	(general
		(thickness 1.6)
		(legacy_teardrops no)
	)
	(paper "A4")
	(title_block
		(title "peb — Lightning_PEB_BRD.brd")
		(comment 1 "Lightning (Wiwynn / Facebook NVMe JBOF) / footprints 23-29 of 2563")
	)
	(layers
		(0 "F.Cu" signal "TOP")
		(4 "In1.Cu" signal "L2GND")
		(6 "In2.Cu" signal "L3")
		(8 "In3.Cu" signal "L4VCC")
		(10 "In4.Cu" signal "L5VCC")
		(12 "In5.Cu" signal "L6")
		(14 "In6.Cu" signal "L7GND")
		(2 "B.Cu" signal "BOTTOM")
		(9 "F.Adhes" user "F.Adhesive")
		(11 "B.Adhes" user "B.Adhesive")
		(13 "F.Paste" user "Package Geometry/Pastemask Top")
		(15 "B.Paste" user "Package Geometry/Pastemask Bottom")
		(5 "F.SilkS" user "Ref Des/Silkscreen Top")
		(7 "B.SilkS" user "Ref Des/Silkscreen Bottom")
		(1 "F.Mask" user "Board Geometry/Soldermask Top")
		(3 "B.Mask" user "Board Geometry/Soldermask Bottom")
		(17 "Dwgs.User" user "User.Drawings")
		(19 "Cmts.User" user "User.Comments")
		(21 "Eco1.User" user "User.Eco1")
		(23 "Eco2.User" user "User.Eco2")
		(25 "Edge.Cuts" user "Board Geometry/Outline")
		(27 "Margin" user)
		(31 "F.CrtYd" user "Package Geometry/Place Bound Top")
		(29 "B.CrtYd" user "Package Geometry/Place Bound Bottom")
		(35 "F.Fab" user "Ref Des/Assembly Top")
		(33 "B.Fab" user "Ref Des/Assembly Bottom")
	)
	(footprint ""
		(layer "F.Cu")
		(at 65.4812 -158.0896 90)
		(property "Reference" "PC19"
			(at 0 0 90)
			(layer "F.SilkS")
			(hide yes)
			(effects
				(font
					(size 1.27 1.27)
				)
			)
		)
		(property "Value" "SC22U6D3V5MX-5-GP"
			(at -0.0762 -6.1214 90)
			(unlocked yes)
			(layer "F.Fab")
			(hide yes)
			(effects
				(font
					(size 1.016 1.016)
					(thickness 0.1524)
				)
			)
		)
		(property "Device Type" "C805H56"
			(at -0.0762 -8.1534 90)
			(unlocked yes)
			(layer "F.Fab")
			(hide yes)
			(effects
				(font
					(size 1.016 1.016)
					(thickness 0.1524)
				)
			)
		)
		(duplicate_pad_numbers_are_jumpers no)
		(fp_line
			(start 0.635 0)
			(end -0.635 0)
			(stroke
				(width 0.508)
				(type default)
			)
			(layer "F.SilkS")
		)
		(fp_rect
			(start -0.9652 1.778)
			(end 0.9652 -1.778)
			(stroke
				(width 0)
				(type default)
			)
			(fill no)
			(layer "F.CrtYd")
		)
		(fp_poly
			(pts
				(xy -0.9652 -1.778) (xy 0.9652 -1.778) (xy 0.9652 1.778) (xy -0.9652 1.778)
			)
			(stroke
				(width 0)
				(type default)
			)
			(fill no)
			(layer "F.Fab")
		)
		(pad "1" smd rect
			(at 0 -0.9652 90)
			(size 1.397 1.143)
			(layers "F.Cu" "F.Mask" "F.Paste")
			(net "P1V53_PWR")
		)
		(pad "2" smd rect
			(at 0 0.9652 90)
			(size 1.397 1.143)
			(layers "F.Cu" "F.Mask" "F.Paste")
			(net "GND")
		)
	)
	(footprint ""
		(layer "F.Cu")
		(at 41.7068 -184.8866 -90)
		(property "Reference" "C692"
			(at 0 0 270)
			(layer "F.SilkS")
			(hide yes)
			(effects
				(font
					(size 1.27 1.27)
				)
			)
		)
		(property "Value" "SC220P50V3JN-GP"
			(at 0 -2.8194 270)
			(unlocked yes)
			(layer "F.Fab")
			(hide yes)
			(effects
				(font
					(size 1.016 1.016)
					(thickness 0.1524)
				)
			)
		)
		(property "Device Type" "C603H36"
			(at 0 -4.3434 270)
			(unlocked yes)
			(layer "F.Fab")
			(hide yes)
			(effects
				(font
					(size 1.016 1.016)
					(thickness 0.1524)
				)
			)
		)
		(duplicate_pad_numbers_are_jumpers no)
		(fp_line
			(start 0.508 0)
			(end -0.508 0)
			(stroke
				(width 0.2032)
				(type default)
			)
			(layer "F.SilkS")
		)
		(fp_rect
			(start -0.5842 1.3335)
			(end 0.5842 -1.3335)
			(stroke
				(width 0)
				(type default)
			)
			(fill no)
			(layer "F.CrtYd")
		)
		(fp_rect
			(start -0.5842 1.3335)
			(end 0.5842 -1.3335)
			(stroke
				(width 0)
				(type default)
			)
			(fill no)
			(layer "F.Fab")
		)
		(pad "1" smd custom
			(at 0 -0.762 270)
			(size 0.2159 0.2159)
			(layers "F.Cu" "F.Mask" "F.Paste")
			(net "BMC_I2C9_CLKBUF2_SDA_R")
			(options
				(clearance outline)
				(anchor circle)
			)
			(primitives
				(gr_poly
					(pts
						(arc
							(start -0.3302 -0.4318)
							(mid -0.402042 -0.402042)
							(end -0.4318 -0.3302)
						)
						(arc
							(start -0.4318 0.3302)
							(mid -0.402042 0.402042)
							(end -0.3302 0.4318)
						)
						(arc
							(start 0.3302 0.4318)
							(mid 0.402042 0.402042)
							(end 0.4318 0.3302)
						)
						(arc
							(start 0.4318 -0.3302)
							(mid 0.402042 -0.402042)
							(end 0.3302 -0.4318)
						)
					)
					(width 0)
					(fill yes)
				)
			)
		)
		(pad "2" smd custom
			(at 0 0.762 270)
			(size 0.2159 0.2159)
			(layers "F.Cu" "F.Mask" "F.Paste")
			(net "GND")
			(options
				(clearance outline)
				(anchor circle)
			)
			(primitives
				(gr_poly
					(pts
						(arc
							(start -0.3302 -0.4318)
							(mid -0.402042 -0.402042)
							(end -0.4318 -0.3302)
						)
						(arc
							(start -0.4318 0.3302)
							(mid -0.402042 0.402042)
							(end -0.3302 0.4318)
						)
						(arc
							(start 0.3302 0.4318)
							(mid 0.402042 0.402042)
							(end 0.4318 0.3302)
						)
						(arc
							(start 0.4318 -0.3302)
							(mid 0.402042 -0.402042)
							(end 0.3302 -0.4318)
						)
					)
					(width 0)
					(fill yes)
				)
			)
		)
	)
	(footprint ""
		(layer "F.Cu")
		(at 221.2086 -205.0034 180)
		(property "Reference" "R9042"
			(at 0 0 180)
			(layer "F.SilkS")
			(hide yes)
			(effects
				(font
					(size 1.27 1.27)
				)
			)
		)
		(property "Value" "4K7R2F-GP"
			(at 0.064008 -3.993896 180)
			(unlocked yes)
			(layer "F.Fab")
			(hide yes)
			(effects
				(font
					(size 1.016 1.016)
					(thickness 0.1524)
				)
			)
		)
		(property "Device Type" "R402H16"
			(at 0.064008 -5.517896 180)
			(unlocked yes)
			(layer "F.Fab")
			(hide yes)
			(effects
				(font
					(size 1.016 1.016)
					(thickness 0.1524)
				)
			)
		)
		(duplicate_pad_numbers_are_jumpers no)
		(fp_line
			(start 0.508 -0.9398)
			(end -0.508 -0.9398)
			(stroke
				(width 0.1524)
				(type default)
			)
			(layer "F.SilkS")
		)
		(fp_line
			(start -0.508 -0.9398)
			(end -0.508 0.9398)
			(stroke
				(width 0.1524)
				(type default)
			)
			(layer "F.SilkS")
		)
		(fp_rect
			(start -0.508 0.9398)
			(end 0.508 -0.9398)
			(stroke
				(width 0)
				(type default)
			)
			(fill no)
			(layer "F.CrtYd")
		)
		(fp_rect
			(start -0.508 0.9398)
			(end 0.508 -0.9398)
			(stroke
				(width 0)
				(type default)
			)
			(fill no)
			(layer "F.Fab")
		)
		(pad "1" smd custom
			(at 0 -0.4445 180)
			(size 0.1397 0.1397)
			(layers "F.Cu" "F.Mask" "F.Paste")
			(net "SSD_PERST#13")
			(options
				(clearance outline)
				(anchor circle)
			)
			(primitives
				(gr_poly
					(pts
						(arc
							(start -0.1778 -0.2794)
							(mid -0.249642 -0.249642)
							(end -0.2794 -0.1778)
						)
						(arc
							(start -0.2794 0.1778)
							(mid -0.249642 0.249642)
							(end -0.1778 0.2794)
						)
						(arc
							(start 0.1778 0.2794)
							(mid 0.249642 0.249642)
							(end 0.2794 0.1778)
						)
						(arc
							(start 0.2794 -0.1778)
							(mid 0.249642 -0.249642)
							(end 0.1778 -0.2794)
						)
					)
					(width 0)
					(fill yes)
				)
			)
		)
		(pad "2" smd custom
			(at 0 0.4445 180)
			(size 0.1397 0.1397)
			(layers "F.Cu" "F.Mask" "F.Paste")
			(net "GND")
			(options
				(clearance outline)
				(anchor circle)
			)
			(primitives
				(gr_poly
					(pts
						(arc
							(start -0.1778 -0.2794)
							(mid -0.249642 -0.249642)
							(end -0.2794 -0.1778)
						)
						(arc
							(start -0.2794 0.1778)
							(mid -0.249642 0.249642)
							(end -0.1778 0.2794)
						)
						(arc
							(start 0.1778 0.2794)
							(mid 0.249642 0.249642)
							(end 0.2794 0.1778)
						)
						(arc
							(start 0.2794 -0.1778)
							(mid 0.249642 -0.249642)
							(end 0.1778 -0.2794)
						)
					)
					(width 0)
					(fill yes)
				)
			)
		)
	)
	(footprint ""
		(layer "F.Cu")
		(at 21.6662 -183.2356 90)
		(property "Reference" "PQ33"
			(at 0 0 90)
			(layer "F.SilkS")
			(hide yes)
			(effects
				(font
					(size 1.27 1.27)
				)
			)
		)
		(property "Value" "MMBT3904FN3-GP-U"
			(at -1.5748 -0.2032 90)
			(unlocked yes)
			(layer "F.Fab")
			(hide yes)
			(effects
				(font
					(size 1.016 1.016)
					(thickness 0.1524)
				)
			)
		)
		(property "Device Type" "SOT883CBE1D0-2U1H22"
			(at -1.5748 -1.7272 90)
			(unlocked yes)
			(layer "F.Fab")
			(hide yes)
			(effects
				(font
					(size 1.016 1.016)
					(thickness 0.1524)
				)
			)
		)
		(duplicate_pad_numbers_are_jumpers no)
		(fp_line
			(start 0.5588 -0.762)
			(end 0.5588 0.762)
			(stroke
				(width 0.1524)
				(type default)
			)
			(layer "F.SilkS")
		)
		(fp_line
			(start -0.5588 -0.762)
			(end 0.5588 -0.762)
			(stroke
				(width 0.1524)
				(type default)
			)
			(layer "F.SilkS")
		)
		(fp_line
			(start 0.5588 0.762)
			(end -0.5588 0.762)
			(stroke
				(width 0.1524)
				(type default)
			)
			(layer "F.SilkS")
		)
		(fp_line
			(start -0.5588 0.762)
			(end -0.5588 -0.762)
			(stroke
				(width 0.1524)
				(type default)
			)
			(layer "F.SilkS")
		)
		(fp_poly
			(pts
				(arc
					(start 0.005842 -0.839978)
					(mid 0.005842 -1.347978)
					(end 0.005842 -0.839978)
				)
			)
			(stroke
				(width 0)
				(type default)
			)
			(fill yes)
			(layer "F.SilkS")
		)
		(fp_rect
			(start -0.2921 0.4953)
			(end 0.2921 -0.4953)
			(stroke
				(width 0)
				(type default)
			)
			(fill no)
			(layer "F.CrtYd")
		)
		(fp_poly
			(pts
				(xy 0.8128 -1.016) (xy 0.8128 1.016) (xy -0.8128 1.016) (xy -0.8128 0.00635) (xy -0.2921 0.00635)
				(xy -0.2921 0.4953) (xy 0.2921 0.4953) (xy 0.2921 -0.4953) (xy -0.2921 -0.4953) (xy -0.2921 -0.00635)
				(xy -0.8128 -0.00635) (xy -0.8128 -1.016)
			)
			(stroke
				(width 0)
				(type default)
			)
			(fill no)
			(layer "F.CrtYd")
		)
		(fp_rect
			(start -0.8128 1.016)
			(end 0.8128 -1.016)
			(stroke
				(width 0)
				(type default)
			)
			(fill no)
			(layer "F.Fab")
		)
		(pad "B" smd rect
			(at -0.2032 0.350012 90)
			(size 0.2032 0.3048)
			(layers "F.Cu" "F.Mask" "F.Paste")
			(net "MB0_TEMP_C")
		)
		(pad "C" smd rect
			(at 0 -0.350012 90)
			(size 0.5588 0.3048)
			(layers "F.Cu" "F.Mask" "F.Paste")
			(net "MB0_TEMP_C")
		)
		(pad "E" smd rect
			(at 0.2032 0.350012 90)
			(size 0.2032 0.3048)
			(layers "F.Cu" "F.Mask" "F.Paste")
			(net "MB0_TEMP_E")
		)
	)
	(footprint ""
		(layer "F.Cu")
		(at 48.811942 -118.38305)
		(property "Reference" "TP154"
			(at 0 0 0)
			(layer "F.SilkS")
			(hide yes)
			(effects
				(font
					(size 1.27 1.27)
				)
			)
		)
		(property "Value" "TPAD28-2-GP"
			(at -0.0127 -1.6637 0)
			(unlocked yes)
			(layer "F.Fab")
			(hide yes)
			(effects
				(font
					(size 1.016 1.016)
					(thickness 0.1524)
				)
			)
		)
		(property "Device Type" "TPAD28"
			(at -0.0127 -3.1877 0)
			(unlocked yes)
			(layer "F.Fab")
			(hide yes)
			(effects
				(font
					(size 1.016 1.016)
					(thickness 0.1524)
				)
			)
		)
		(duplicate_pad_numbers_are_jumpers no)
		(fp_poly
			(pts
				(arc
					(start 0.3556 0)
					(mid -0.3556 0)
					(end 0.3556 0)
				)
			)
			(stroke
				(width 0)
				(type default)
			)
			(fill no)
			(layer "F.CrtYd")
		)
		(fp_poly
			(pts
				(arc
					(start 0.6096 0)
					(mid -0.6096 0)
					(end 0.6096 0)
				)
			)
			(stroke
				(width 0)
				(type default)
			)
			(fill no)
			(layer "F.Fab")
		)
		(pad "1" smd circle
			(at 0 0)
			(size 0.7112 0.7112)
			(layers "F.Cu" "F.Mask" "F.Paste")
			(net "TP_GPIOA6")
		)
	)
	(footprint ""
		(layer "F.Cu")
		(at 187.10402 -16.23314 -90)
		(property "Reference" "SR719"
			(at 0 0 270)
			(layer "F.SilkS")
			(hide yes)
			(effects
				(font
					(size 1.27 1.27)
				)
			)
		)
		(property "Value" "150R2F-1-GP"
			(at 0.064008 -3.993896 270)
			(unlocked yes)
			(layer "F.Fab")
			(hide yes)
			(effects
				(font
					(size 1.016 1.016)
					(thickness 0.1524)
				)
			)
		)
		(property "Device Type" "R402H16"
			(at 0.064008 -5.517896 270)
			(unlocked yes)
			(layer "F.Fab")
			(hide yes)
			(effects
				(font
					(size 1.016 1.016)
					(thickness 0.1524)
				)
			)
		)
		(duplicate_pad_numbers_are_jumpers no)
		(fp_line
			(start -0.508 -0.9398)
			(end -0.508 0.9398)
			(stroke
				(width 0.1524)
				(type default)
			)
			(layer "F.SilkS")
		)
		(fp_line
			(start 0.508 -0.9398)
			(end -0.508 -0.9398)
			(stroke
				(width 0.1524)
				(type default)
			)
			(layer "F.SilkS")
		)
		(fp_rect
			(start -0.508 0.9398)
			(end 0.508 -0.9398)
			(stroke
				(width 0)
				(type default)
			)
			(fill no)
			(layer "F.CrtYd")
		)
		(fp_rect
			(start -0.508 0.9398)
			(end 0.508 -0.9398)
			(stroke
				(width 0)
				(type default)
			)
			(fill no)
			(layer "F.Fab")
		)
		(pad "1" smd custom
			(at 0 -0.4445 270)
			(size 0.1397 0.1397)
			(layers "F.Cu" "F.Mask" "F.Paste")
			(net "P3V3_STBY")
			(options
				(clearance outline)
				(anchor circle)
			)
			(primitives
				(gr_poly
					(pts
						(arc
							(start -0.1778 -0.2794)
							(mid -0.249642 -0.249642)
							(end -0.2794 -0.1778)
						)
						(arc
							(start -0.2794 0.1778)
							(mid -0.249642 0.249642)
							(end -0.1778 0.2794)
						)
						(arc
							(start 0.1778 0.2794)
							(mid 0.249642 0.249642)
							(end 0.2794 0.1778)
						)
						(arc
							(start 0.2794 -0.1778)
							(mid 0.249642 -0.249642)
							(end 0.1778 -0.2794)
						)
					)
					(width 0)
					(fill yes)
				)
			)
		)
		(pad "2" smd custom
			(at 0 0.4445 270)
			(size 0.1397 0.1397)
			(layers "F.Cu" "F.Mask" "F.Paste")
			(net "LED_R_10")
			(options
				(clearance outline)
				(anchor circle)
			)
			(primitives
				(gr_poly
					(pts
						(arc
							(start -0.1778 -0.2794)
							(mid -0.249642 -0.249642)
							(end -0.2794 -0.1778)
						)
						(arc
							(start -0.2794 0.1778)
							(mid -0.249642 0.249642)
							(end -0.1778 0.2794)
						)
						(arc
							(start 0.1778 0.2794)
							(mid 0.249642 0.249642)
							(end 0.2794 0.1778)
						)
						(arc
							(start 0.2794 -0.1778)
							(mid 0.249642 -0.249642)
							(end 0.1778 -0.2794)
						)
					)
					(width 0)
					(fill yes)
				)
			)
		)
	)
	(footprint ""
		(layer "F.Cu")
		(at 9.4996 -100.1014 -90)
		(property "Reference" "R400"
			(at 0 0 270)
			(layer "F.SilkS")
			(hide yes)
			(effects
				(font
					(size 1.27 1.27)
				)
			)
		)
		(property "Value" "10KR2F-2-GP"
			(at 0.064008 -3.993896 270)
			(unlocked yes)
			(layer "F.Fab")
			(hide yes)
			(effects
				(font
					(size 1.016 1.016)
					(thickness 0.1524)
				)
			)
		)
		(property "Device Type" "R402H16"
			(at 0.064008 -5.517896 270)
			(unlocked yes)
			(layer "F.Fab")
			(hide yes)
			(effects
				(font
					(size 1.016 1.016)
					(thickness 0.1524)
				)
			)
		)
		(duplicate_pad_numbers_are_jumpers no)
		(fp_line
			(start -0.508 -0.9398)
			(end -0.508 0.9398)
			(stroke
				(width 0.1524)
				(type default)
			)
			(layer "F.SilkS")
		)
		(fp_line
			(start 0.508 -0.9398)
			(end -0.508 -0.9398)
			(stroke
				(width 0.1524)
				(type default)
			)
			(layer "F.SilkS")
		)
		(fp_rect
			(start -0.508 0.9398)
			(end 0.508 -0.9398)
			(stroke
				(width 0)
				(type default)
			)
			(fill no)
			(layer "F.CrtYd")
		)
		(fp_rect
			(start -0.508 0.9398)
			(end 0.508 -0.9398)
			(stroke
				(width 0)
				(type default)
			)
			(fill no)
			(layer "F.Fab")
		)
		(pad "1" smd custom
			(at 0 -0.4445 270)
			(size 0.1397 0.1397)
			(layers "F.Cu" "F.Mask" "F.Paste")
			(net "P3V3_STBY")
			(options
				(clearance outline)
				(anchor circle)
			)
			(primitives
				(gr_poly
					(pts
						(arc
							(start -0.1778 -0.2794)
							(mid -0.249642 -0.249642)
							(end -0.2794 -0.1778)
						)
						(arc
							(start -0.2794 0.1778)
							(mid -0.249642 0.249642)
							(end -0.1778 0.2794)
						)
						(arc
							(start 0.1778 0.2794)
							(mid 0.249642 0.249642)
							(end 0.2794 0.1778)
						)
						(arc
							(start 0.2794 -0.1778)
							(mid 0.249642 -0.249642)
							(end 0.1778 -0.2794)
						)
					)
					(width 0)
					(fill yes)
				)
			)
		)
		(pad "2" smd custom
			(at 0 0.4445 270)
			(size 0.1397 0.1397)
			(layers "F.Cu" "F.Mask" "F.Paste")
			(net "50M_CLK_OE")
			(options
				(clearance outline)
				(anchor circle)
			)
			(primitives
				(gr_poly
					(pts
						(arc
							(start -0.1778 -0.2794)
							(mid -0.249642 -0.249642)
							(end -0.2794 -0.1778)
						)
						(arc
							(start -0.2794 0.1778)
							(mid -0.249642 0.249642)
							(end -0.1778 0.2794)
						)
						(arc
							(start 0.1778 0.2794)
							(mid 0.249642 0.249642)
							(end 0.2794 0.1778)
						)
						(arc
							(start 0.2794 -0.1778)
							(mid 0.249642 -0.249642)
							(end 0.1778 -0.2794)
						)
					)
					(width 0)
					(fill yes)
				)
			)
		)
	)
)
